# T6G (Grand Teton) — schematic netlist excerpt (pin names and nets, part order shuffled) for the footprints in the layout excerpt that follows; sources: Cadence DE-HDL packaged netlist, KiCad conversion of 04192023_DAF0TMB3IC0_F0TG_MB_C_brd_V02_OCP.brd

PC146  Q_CAP  0.22UF 16V 10% X7R  pkg 0402  page 220 : A = SW_PVDDCR_CPU1_P1_BOOT6_R ; B = SW_PVDDCR_CPU1_P1_BOOTR6
R783  Q_RES  10K 1% CHIP  pkg 0201LF  page 331 : A = GPIO3_RT_CPU1_P1 ; B = GND
PC139_C1P1_6  Q_CAP  2.2UF 10V 10% X6S  pkg C0402  page 220 : A = PVDDCR_CPU1_P1_PVCC ; B = GND

(kicad_pcb
	(version 20260206)
	(generator "pcbnew")
	(generator_version "10.0")
	(general
		(thickness 1.6)
		(legacy_teardrops no)
	)
	(paper "A4")
	(title_block
		(title "04192023_DAF0TMB3IC0_F0TG_MB_C_brd_V02_OCP.brd")
		(comment 1 "Grand Teton / footprints 2002-2004 of 8354")
	)
	(layers
		(0 "F.Cu" signal "TOP")
		(4 "In1.Cu" signal "GND")
		(6 "In2.Cu" signal "IN1")
		(8 "In3.Cu" signal "GND1")
		(10 "In4.Cu" signal "IN2")
		(12 "In5.Cu" signal "GND2")
		(14 "In6.Cu" signal "IN3")
		(16 "In7.Cu" signal "GND3")
		(18 "In8.Cu" signal "VCC")
		(20 "In9.Cu" signal "VCC1")
		(22 "In10.Cu" signal "GND4")
		(24 "In11.Cu" signal "IN4")
		(26 "In12.Cu" signal "GND5")
		(28 "In13.Cu" signal "IN5")
		(30 "In14.Cu" signal "GND6")
		(32 "In15.Cu" signal "IN6")
		(34 "In16.Cu" signal "GND7")
		(2 "B.Cu" signal "BOTTOM")
		(9 "F.Adhes" user "F.Adhesive")
		(11 "B.Adhes" user "B.Adhesive")
		(13 "F.Paste" user "Package Geometry/Pastemask Top")
		(15 "B.Paste" user "Package Geometry/Pastemask Bottom")
		(5 "F.SilkS" user "Ref Des/Silkscreen Top")
		(7 "B.SilkS" user "Ref Des/Silkscreen Bottom")
		(1 "F.Mask" user "Board Geometry/Soldermask Top")
		(3 "B.Mask" user "Board Geometry/Soldermask Bottom")
		(17 "Dwgs.User" user "User.Drawings")
		(19 "Cmts.User" user "User.Comments")
		(21 "Eco1.User" user "User.Eco1")
		(23 "Eco2.User" user "User.Eco2")
		(25 "Edge.Cuts" user "Board Geometry/Outline")
		(27 "Margin" user)
		(31 "F.CrtYd" user "Package Geometry/Place Bound Top")
		(29 "B.CrtYd" user "Package Geometry/Place Bound Bottom")
		(35 "F.Fab" user "Ref Des/Assembly Top")
		(33 "B.Fab" user "Ref Des/Assembly Bottom")
	)
	(footprint ""
		(layer "F.Cu")
		(at 105.515156 -344.591132 -90)
		(property "Reference" "PC146"
			(at 0 0 270)
			(layer "F.SilkS")
			(hide yes)
			(effects
				(font
					(size 1.27 1.27)
				)
			)
		)
		(property "Value" ""
			(at 0 0 270)
			(layer "F.Fab")
			(effects
				(font
					(size 1.27 1.27)
				)
			)
		)
		(duplicate_pad_numbers_are_jumpers no)
		(fp_line
			(start -0.7874 0.4064)
			(end -0.7874 -0.4064)
			(stroke
				(width 0.1524)
				(type default)
			)
			(layer "F.SilkS")
		)
		(fp_line
			(start 0.7874 0.4064)
			(end -0.7874 0.4064)
			(stroke
				(width 0.1524)
				(type default)
			)
			(layer "F.SilkS")
		)
		(fp_line
			(start -0.7874 -0.4064)
			(end 0.7874 -0.4064)
			(stroke
				(width 0.1524)
				(type default)
			)
			(layer "F.SilkS")
		)
		(fp_line
			(start 0.7874 -0.4064)
			(end 0.7874 0.4064)
			(stroke
				(width 0.1524)
				(type default)
			)
			(layer "F.SilkS")
		)
		(fp_line
			(start -0.67945 0.3048)
			(end -0.67945 -0.305054)
			(stroke
				(width 0.1)
				(type default)
			)
			(layer "F.Fab")
		)
		(fp_line
			(start -0.12065 0.3048)
			(end -0.67945 0.3048)
			(stroke
				(width 0.1)
				(type default)
			)
			(layer "F.Fab")
		)
		(fp_line
			(start 0.120396 0.3048)
			(end 0.120396 0.2794)
			(stroke
				(width 0.1)
				(type default)
			)
			(layer "F.Fab")
		)
		(fp_line
			(start 0.67945 0.3048)
			(end 0.120396 0.3048)
			(stroke
				(width 0.1)
				(type default)
			)
			(layer "F.Fab")
		)
		(fp_line
			(start -0.12065 0.2794)
			(end -0.12065 0.3048)
			(stroke
				(width 0.1)
				(type default)
			)
			(layer "F.Fab")
		)
		(fp_line
			(start 0.120396 0.2794)
			(end -0.12065 0.2794)
			(stroke
				(width 0.1)
				(type default)
			)
			(layer "F.Fab")
		)
		(fp_line
			(start -0.12065 -0.2794)
			(end 0.12065 -0.2794)
			(stroke
				(width 0.1)
				(type default)
			)
			(layer "F.Fab")
		)
		(fp_line
			(start 0.12065 -0.2794)
			(end 0.12065 -0.3048)
			(stroke
				(width 0.1)
				(type default)
			)
			(layer "F.Fab")
		)
		(fp_line
			(start 0.12065 -0.3048)
			(end 0.67945 -0.3048)
			(stroke
				(width 0.1)
				(type default)
			)
			(layer "F.Fab")
		)
		(fp_line
			(start 0.67945 -0.3048)
			(end 0.67945 0.3048)
			(stroke
				(width 0.1)
				(type default)
			)
			(layer "F.Fab")
		)
		(fp_line
			(start -0.67945 -0.305054)
			(end -0.12065 -0.305054)
			(stroke
				(width 0.1)
				(type default)
			)
			(layer "F.Fab")
		)
		(fp_line
			(start -0.12065 -0.305054)
			(end -0.12065 -0.2794)
			(stroke
				(width 0.1)
				(type default)
			)
			(layer "F.Fab")
		)
		(pad "1" smd circle
			(at -0.40005 0 270)
			(size 0 0)
			(layers "F.Cu" "F.Mask" "F.Paste")
			(net "SW_PVDDCR_CPU1_P1_BOOT6_R")
		)
		(pad "2" smd circle
			(at 0.40005 0 270)
			(size 0 0)
			(layers "F.Cu" "F.Mask" "F.Paste")
			(net "SW_PVDDCR_CPU1_P1_BOOTR6")
		)
	)
	(footprint ""
		(layer "F.Cu")
		(at 75.7936 -384.66268)
		(property "Reference" "R783"
			(at 0 0 0)
			(layer "F.SilkS")
			(hide yes)
			(effects
				(font
					(size 1.27 1.27)
				)
			)
		)
		(property "Value" ""
			(at 0 0 0)
			(layer "F.Fab")
			(effects
				(font
					(size 1.27 1.27)
				)
			)
		)
		(duplicate_pad_numbers_are_jumpers no)
		(fp_line
			(start -0.32512 -0.175006)
			(end 0.32512 -0.175006)
			(stroke
				(width 0.1)
				(type default)
			)
			(layer "F.Fab")
		)
		(fp_line
			(start -0.32512 0.175006)
			(end -0.32512 -0.175006)
			(stroke
				(width 0.1)
				(type default)
			)
			(layer "F.Fab")
		)
		(fp_line
			(start 0.32512 -0.175006)
			(end 0.32512 0.175006)
			(stroke
				(width 0.1)
				(type default)
			)
			(layer "F.Fab")
		)
		(fp_line
			(start 0.32512 0.175006)
			(end -0.32512 0.175006)
			(stroke
				(width 0.1)
				(type default)
			)
			(layer "F.Fab")
		)
		(pad "1" smd rect
			(at -0.2667 0)
			(size 0.3048 0.381)
			(layers "F.Cu" "F.Mask" "F.Paste")
			(net "GPIO3_RT_CPU1_P1")
		)
		(pad "2" smd rect
			(at 0.2667 0 180)
			(size 0.3048 0.381)
			(layers "F.Cu" "F.Mask" "F.Paste")
			(net "GND")
		)
	)
	(footprint ""
		(layer "F.Cu")
		(at 100.046282 -339.937598 -90)
		(property "Reference" "PC139_C1P1_6"
			(at 0 0 270)
			(layer "F.SilkS")
			(hide yes)
			(effects
				(font
					(size 1.27 1.27)
				)
			)
		)
		(property "Value" ""
			(at 0 0 270)
			(layer "F.Fab")
			(effects
				(font
					(size 1.27 1.27)
				)
			)
		)
		(duplicate_pad_numbers_are_jumpers no)
		(fp_line
			(start -0.7874 0.4064)
			(end -0.7874 -0.4064)
			(stroke
				(width 0.1524)
				(type default)
			)
			(layer "F.SilkS")
		)
		(fp_line
			(start 0.7874 0.4064)
			(end -0.7874 0.4064)
			(stroke
				(width 0.1524)
				(type default)
			)
			(layer "F.SilkS")
		)
		(fp_line
			(start -0.7874 -0.4064)
			(end 0.7874 -0.4064)
			(stroke
				(width 0.1524)
				(type default)
			)
			(layer "F.SilkS")
		)
		(fp_line
			(start 0.7874 -0.4064)
			(end 0.7874 0.4064)
			(stroke
				(width 0.1524)
				(type default)
			)
			(layer "F.SilkS")
		)
		(fp_line
			(start -0.67945 0.3048)
			(end -0.67945 -0.305054)
			(stroke
				(width 0.1)
				(type default)
			)
			(layer "F.Fab")
		)
		(fp_line
			(start -0.12065 0.3048)
			(end -0.67945 0.3048)
			(stroke
				(width 0.1)
				(type default)
			)
			(layer "F.Fab")
		)
		(fp_line
			(start 0.120396 0.3048)
			(end 0.120396 0.2794)
			(stroke
				(width 0.1)
				(type default)
			)
			(layer "F.Fab")
		)
		(fp_line
			(start 0.67945 0.3048)
			(end 0.120396 0.3048)
			(stroke
				(width 0.1)
				(type default)
			)
			(layer "F.Fab")
		)
		(fp_line
			(start -0.12065 0.2794)
			(end -0.12065 0.3048)
			(stroke
				(width 0.1)
				(type default)
			)
			(layer "F.Fab")
		)
		(fp_line
			(start 0.120396 0.2794)
			(end -0.12065 0.2794)
			(stroke
				(width 0.1)
				(type default)
			)
			(layer "F.Fab")
		)
		(fp_line
			(start -0.12065 -0.2794)
			(end 0.12065 -0.2794)
			(stroke
				(width 0.1)
				(type default)
			)
			(layer "F.Fab")
		)
		(fp_line
			(start 0.12065 -0.2794)
			(end 0.12065 -0.3048)
			(stroke
				(width 0.1)
				(type default)
			)
			(layer "F.Fab")
		)
		(fp_line
			(start 0.12065 -0.3048)
			(end 0.67945 -0.3048)
			(stroke
				(width 0.1)
				(type default)
			)
			(layer "F.Fab")
		)
		(fp_line
			(start 0.67945 -0.3048)
			(end 0.67945 0.3048)
			(stroke
				(width 0.1)
				(type default)
			)
			(layer "F.Fab")
		)
		(fp_line
			(start -0.67945 -0.305054)
			(end -0.12065 -0.305054)
			(stroke
				(width 0.1)
				(type default)
			)
			(layer "F.Fab")
		)
		(fp_line
			(start -0.12065 -0.305054)
			(end -0.12065 -0.2794)
			(stroke
				(width 0.1)
				(type default)
			)
			(layer "F.Fab")
		)
		(pad "1" smd circle
			(at -0.40005 0 270)
			(size 0 0)
			(layers "F.Cu" "F.Mask" "F.Paste")
			(net "PVDDCR_CPU1_P1_PVCC")
		)
		(pad "2" smd circle
			(at 0.40005 0 270)
			(size 0 0)
			(layers "F.Cu" "F.Mask" "F.Paste")
			(net "GND")
		)
	)
)
